(kicad_pcb
	(version 20260206)
	(generator "pcbnew")
	(generator_version "10.0")
	(general
		(thickness 1.6)
		(legacy_teardrops no)
	)
	(paper "A4")
	(title_block
		(title "peb — Lightning_PEB_BRD.brd")
		(comment 1 "Lightning (Wiwynn / Facebook NVMe JBOF) / footprints 93-99 of 2563")
	)
	(layers
		(0 "F.Cu" signal "TOP")
		(4 "In1.Cu" signal "L2GND")
		(6 "In2.Cu" signal "L3")
		(8 "In3.Cu" signal "L4VCC")
		(10 "In4.Cu" signal "L5VCC")
		(12 "In5.Cu" signal "L6")
		(14 "In6.Cu" signal "L7GND")
		(2 "B.Cu" signal "BOTTOM")
		(9 "F.Adhes" user "F.Adhesive")
		(11 "B.Adhes" user "B.Adhesive")
		(13 "F.Paste" user "Package Geometry/Pastemask Top")
		(15 "B.Paste" user "Package Geometry/Pastemask Bottom")
		(5 "F.SilkS" user "Ref Des/Silkscreen Top")
		(7 "B.SilkS" user "Ref Des/Silkscreen Bottom")
		(1 "F.Mask" user "Board Geometry/Soldermask Top")
		(3 "B.Mask" user "Board Geometry/Soldermask Bottom")
		(17 "Dwgs.User" user "User.Drawings")
		(19 "Cmts.User" user "User.Comments")
		(21 "Eco1.User" user "User.Eco1")
		(23 "Eco2.User" user "User.Eco2")
		(25 "Edge.Cuts" user "Board Geometry/Outline")
		(27 "Margin" user)
		(31 "F.CrtYd" user "Package Geometry/Place Bound Top")
		(29 "B.CrtYd" user "Package Geometry/Place Bound Bottom")
		(35 "F.Fab" user "Ref Des/Assembly Top")
		(33 "B.Fab" user "Ref Des/Assembly Bottom")
	)
	(footprint ""
		(layer "F.Cu")
		(at 120.200674 -64.83223 -90)
		(property "Reference" "BAT1"
			(at 0 0 270)
			(layer "F.SilkS")
			(hide yes)
			(effects
				(font
					(size 1.27 1.27)
				)
			)
		)
		(property "Value" "AAA-BAT-043-K03-GP"
			(at -10.2616 -6.7056 270)
			(unlocked yes)
			(layer "F.Fab")
			(hide yes)
			(effects
				(font
					(size 1.016 1.016)
					(thickness 0.1524)
				)
			)
		)
		(property "Device Type" "AAA-BAT-043-K01"
			(at -10.2616 -8.2296 270)
			(unlocked yes)
			(layer "F.Fab")
			(hide yes)
			(effects
				(font
					(size 1.016 1.016)
					(thickness 0.1524)
				)
			)
		)
		(duplicate_pad_numbers_are_jumpers no)
		(fp_line
			(start -5.38099 2.0574)
			(end -4.61899 2.0574)
			(stroke
				(width 0.1524)
				(type default)
			)
			(layer "F.SilkS")
		)
		(fp_line
			(start 4.61899 2.0574)
			(end 5.38099 2.0574)
			(stroke
				(width 0.1524)
				(type default)
			)
			(layer "F.SilkS")
		)
		(fp_line
			(start -4.99999 1.6764)
			(end -4.99999 2.4384)
			(stroke
				(width 0.1524)
				(type default)
			)
			(layer "F.SilkS")
		)
		(fp_line
			(start 4.99999 1.6764)
			(end 4.99999 2.4384)
			(stroke
				(width 0.1524)
				(type default)
			)
			(layer "F.SilkS")
		)
		(fp_line
			(start 10.7569 1.4732)
			(end 12.0269 1.4732)
			(stroke
				(width 0.4064)
				(type default)
			)
			(layer "F.SilkS")
		)
		(fp_line
			(start 12.0269 1.4732)
			(end 12.0269 0.2032)
			(stroke
				(width 0.4064)
				(type default)
			)
			(layer "F.SilkS")
		)
		(fp_line
			(start -11.8999 1.3462)
			(end -11.8999 -4.953)
			(stroke
				(width 0.1524)
				(type default)
			)
			(layer "F.SilkS")
		)
		(fp_line
			(start 11.8999 1.3462)
			(end -11.8999 1.3462)
			(stroke
				(width 0.1524)
				(type default)
			)
			(layer "F.SilkS")
		)
		(fp_line
			(start -11.8999 -4.953)
			(end 11.8999 -4.953)
			(stroke
				(width 0.1524)
				(type default)
			)
			(layer "F.SilkS")
		)
		(fp_line
			(start 11.8999 -4.953)
			(end 11.8999 1.3462)
			(stroke
				(width 0.1524)
				(type default)
			)
			(layer "F.SilkS")
		)
		(fp_line
			(start -0.381 -5.301234)
			(end 0.381 -5.301234)
			(stroke
				(width 0.1524)
				(type default)
			)
			(layer "F.SilkS")
		)
		(fp_circle
			(center -4.99999 0)
			(end -4.99999 -1.0922)
			(stroke
				(width 0.3048)
				(type default)
			)
			(fill no)
			(layer "F.SilkS")
		)
		(fp_circle
			(center 4.99999 0)
			(end 4.99999 -1.0922)
			(stroke
				(width 0.3048)
				(type default)
			)
			(fill no)
			(layer "F.SilkS")
		)
		(fp_circle
			(center 0 -3.599942)
			(end 0 -4.692142)
			(stroke
				(width 0.3048)
				(type default)
			)
			(fill no)
			(layer "F.SilkS")
		)
		(fp_rect
			(start -11.6459 1.0922)
			(end 11.6459 -4.699)
			(stroke
				(width 0)
				(type default)
			)
			(fill no)
			(layer "F.CrtYd")
		)
		(fp_poly
			(pts
				(xy -0.1016 -5.207) (xy -0.1016 -4.699) (xy 11.6459 -4.699) (xy 11.6459 1.0922) (xy -11.6459 1.0922)
				(xy -11.6459 -4.699) (xy -0.1143 -4.699) (xy -0.1143 -5.207) (xy -12.1539 -5.207) (xy -12.1539 1.6002)
				(xy 12.1539 1.6002) (xy 12.1539 -5.207)
			)
			(stroke
				(width 0)
				(type default)
			)
			(fill no)
			(layer "F.CrtYd")
		)
		(fp_rect
			(start -12.1539 1.6002)
			(end 12.1539 -5.207)
			(stroke
				(width 0)
				(type default)
			)
			(fill no)
			(layer "F.Fab")
		)
		(pad "1" thru_hole circle
			(at 4.99999 0 270)
			(size 1.4732 1.4732)
			(drill 1.0668)
			(layers "*.Cu" "*.Mask")
			(remove_unused_layers no)
			(net "P3V0_BAT")
			(clearance 0.1524)
			(thermal_gap 0.1524)
		)
		(pad "2" thru_hole circle
			(at 0 -3.599942 270)
			(size 1.4732 1.4732)
			(drill 1.0668)
			(layers "*.Cu" "*.Mask")
			(remove_unused_layers no)
			(net "GND")
			(clearance 0.1524)
			(thermal_gap 0.1524)
		)
		(pad "3" thru_hole circle
			(at -4.99999 0 270)
			(size 1.4732 1.4732)
			(drill 1.0668)
			(layers "*.Cu" "*.Mask")
			(remove_unused_layers no)
			(net "P3V0_BAT")
			(clearance 0.1524)
			(thermal_gap 0.1524)
		)
	)
	(footprint ""
		(layer "F.Cu")
		(at 335.026 -71.247)
		(property "Reference" "PC187"
			(at 0 0 0)
			(layer "F.SilkS")
			(hide yes)
			(effects
				(font
					(size 1.27 1.27)
				)
			)
		)
		(property "Value" "SC1U10V2KX-1GP"
			(at 1.1811 -2.7051 0)
			(unlocked yes)
			(layer "F.Fab")
			(hide yes)
			(effects
				(font
					(size 1.016 1.016)
					(thickness 0.1524)
				)
			)
		)
		(property "Device Type" "C402H22"
			(at 1.1811 -4.2291 0)
			(unlocked yes)
			(layer "F.Fab")
			(hide yes)
			(effects
				(font
					(size 1.016 1.016)
					(thickness 0.1524)
				)
			)
		)
		(duplicate_pad_numbers_are_jumpers no)
		(fp_rect
			(start -0.4318 0.9525)
			(end 0.4318 -0.9525)
			(stroke
				(width 0)
				(type default)
			)
			(fill no)
			(layer "F.CrtYd")
		)
		(fp_rect
			(start -0.4318 0.9525)
			(end 0.4318 -0.9525)
			(stroke
				(width 0)
				(type default)
			)
			(fill no)
			(layer "F.Fab")
		)
		(pad "1" smd custom
			(at 0 -0.4445)
			(size 0.1524 0.1524)
			(layers "F.Cu" "F.Mask" "F.Paste")
			(net "GND")
			(options
				(clearance outline)
				(anchor circle)
			)
			(primitives
				(gr_poly
					(pts
						(arc
							(start 0.3048 -0.2032)
							(mid 0.275042 -0.275042)
							(end 0.2032 -0.3048)
						)
						(arc
							(start -0.2032 -0.3048)
							(mid -0.275042 -0.275042)
							(end -0.3048 -0.2032)
						)
						(arc
							(start -0.3048 0.2032)
							(mid -0.275042 0.275042)
							(end -0.2032 0.3048)
						)
						(arc
							(start 0.2032 0.3048)
							(mid 0.275042 0.275042)
							(end 0.3048 0.2032)
						)
					)
					(width 0)
					(fill yes)
				)
			)
		)
		(pad "2" smd custom
			(at 0 0.4445)
			(size 0.1524 0.1524)
			(layers "F.Cu" "F.Mask" "F.Paste")
			(net "P0V9_E_EN")
			(options
				(clearance outline)
				(anchor circle)
			)
			(primitives
				(gr_poly
					(pts
						(arc
							(start 0.3048 -0.2032)
							(mid 0.275042 -0.275042)
							(end 0.2032 -0.3048)
						)
						(arc
							(start -0.2032 -0.3048)
							(mid -0.275042 -0.275042)
							(end -0.3048 -0.2032)
						)
						(arc
							(start -0.3048 0.2032)
							(mid -0.275042 0.275042)
							(end -0.2032 0.3048)
						)
						(arc
							(start 0.2032 0.3048)
							(mid 0.275042 0.275042)
							(end 0.3048 0.2032)
						)
					)
					(width 0)
					(fill yes)
				)
			)
		)
	)
	(footprint ""
		(layer "F.Cu")
		(at 36.528502 -81.8769 -90)
		(property "Reference" "R735"
			(at 0 0 270)
			(layer "F.SilkS")
			(hide yes)
			(effects
				(font
					(size 1.27 1.27)
				)
			)
		)
		(property "Value" "10KR2F-2-GP"
			(at 0.064008 -3.993896 270)
			(unlocked yes)
			(layer "F.Fab")
			(hide yes)
			(effects
				(font
					(size 1.016 1.016)
					(thickness 0.1524)
				)
			)
		)
		(property "Device Type" "R402H16"
			(at 0.064008 -5.517896 270)
			(unlocked yes)
			(layer "F.Fab")
			(hide yes)
			(effects
				(font
					(size 1.016 1.016)
					(thickness 0.1524)
				)
			)
		)
		(duplicate_pad_numbers_are_jumpers no)
		(fp_line
			(start -0.508 -0.9398)
			(end -0.508 0.9398)
			(stroke
				(width 0.1524)
				(type default)
			)
			(layer "F.SilkS")
		)
		(fp_line
			(start 0.508 -0.9398)
			(end -0.508 -0.9398)
			(stroke
				(width 0.1524)
				(type default)
			)
			(layer "F.SilkS")
		)
		(fp_rect
			(start -0.508 0.9398)
			(end 0.508 -0.9398)
			(stroke
				(width 0)
				(type default)
			)
			(fill no)
			(layer "F.CrtYd")
		)
		(fp_rect
			(start -0.508 0.9398)
			(end 0.508 -0.9398)
			(stroke
				(width 0)
				(type default)
			)
			(fill no)
			(layer "F.Fab")
		)
		(pad "1" smd custom
			(at 0 -0.4445 270)
			(size 0.1397 0.1397)
			(layers "F.Cu" "F.Mask" "F.Paste")
			(net "Q45_D")
			(options
				(clearance outline)
				(anchor circle)
			)
			(primitives
				(gr_poly
					(pts
						(arc
							(start -0.1778 -0.2794)
							(mid -0.249642 -0.249642)
							(end -0.2794 -0.1778)
						)
						(arc
							(start -0.2794 0.1778)
							(mid -0.249642 0.249642)
							(end -0.1778 0.2794)
						)
						(arc
							(start 0.1778 0.2794)
							(mid 0.249642 0.249642)
							(end 0.2794 0.1778)
						)
						(arc
							(start 0.2794 -0.1778)
							(mid 0.249642 -0.249642)
							(end 0.1778 -0.2794)
						)
					)
					(width 0)
					(fill yes)
				)
			)
		)
		(pad "2" smd custom
			(at 0 0.4445 270)
			(size 0.1397 0.1397)
			(layers "F.Cu" "F.Mask" "F.Paste")
			(net "Q46_G")
			(options
				(clearance outline)
				(anchor circle)
			)
			(primitives
				(gr_poly
					(pts
						(arc
							(start -0.1778 -0.2794)
							(mid -0.249642 -0.249642)
							(end -0.2794 -0.1778)
						)
						(arc
							(start -0.2794 0.1778)
							(mid -0.249642 0.249642)
							(end -0.1778 0.2794)
						)
						(arc
							(start 0.1778 0.2794)
							(mid 0.249642 0.249642)
							(end 0.2794 0.1778)
						)
						(arc
							(start 0.2794 -0.1778)
							(mid 0.249642 -0.249642)
							(end 0.1778 -0.2794)
						)
					)
					(width 0)
					(fill yes)
				)
			)
		)
	)
	(footprint ""
		(layer "F.Cu")
		(at 120.9548 -91.7702)
		(property "Reference" "R863"
			(at 0 0 0)
			(layer "F.SilkS")
			(hide yes)
			(effects
				(font
					(size 1.27 1.27)
				)
			)
		)
		(property "Value" "0R2J-2-GP"
			(at 0.064008 -3.993896 0)
			(unlocked yes)
			(layer "F.Fab")
			(hide yes)
			(effects
				(font
					(size 1.016 1.016)
					(thickness 0.1524)
				)
			)
		)
		(property "Device Type" "R402H16"
			(at 0.064008 -5.517896 0)
			(unlocked yes)
			(layer "F.Fab")
			(hide yes)
			(effects
				(font
					(size 1.016 1.016)
					(thickness 0.1524)
				)
			)
		)
		(duplicate_pad_numbers_are_jumpers no)
		(fp_line
			(start -0.508 -0.9398)
			(end -0.508 0.9398)
			(stroke
				(width 0.1524)
				(type default)
			)
			(layer "F.SilkS")
		)
		(fp_line
			(start 0.508 -0.9398)
			(end -0.508 -0.9398)
			(stroke
				(width 0.1524)
				(type default)
			)
			(layer "F.SilkS")
		)
		(fp_rect
			(start -0.508 0.9398)
			(end 0.508 -0.9398)
			(stroke
				(width 0)
				(type default)
			)
			(fill no)
			(layer "F.CrtYd")
		)
		(fp_rect
			(start -0.508 0.9398)
			(end 0.508 -0.9398)
			(stroke
				(width 0)
				(type default)
			)
			(fill no)
			(layer "F.Fab")
		)
		(pad "1" smd custom
			(at 0 -0.4445)
			(size 0.1397 0.1397)
			(layers "F.Cu" "F.Mask" "F.Paste")
			(net "BMC_I2C10_8536_SDA_R")
			(options
				(clearance outline)
				(anchor circle)
			)
			(primitives
				(gr_poly
					(pts
						(arc
							(start -0.1778 -0.2794)
							(mid -0.249642 -0.249642)
							(end -0.2794 -0.1778)
						)
						(arc
							(start -0.2794 0.1778)
							(mid -0.249642 0.249642)
							(end -0.1778 0.2794)
						)
						(arc
							(start 0.1778 0.2794)
							(mid 0.249642 0.249642)
							(end 0.2794 0.1778)
						)
						(arc
							(start 0.2794 -0.1778)
							(mid 0.249642 -0.249642)
							(end 0.1778 -0.2794)
						)
					)
					(width 0)
					(fill yes)
				)
			)
		)
		(pad "2" smd custom
			(at 0 0.4445)
			(size 0.1397 0.1397)
			(layers "F.Cu" "F.Mask" "F.Paste")
			(net "BMC_I2C10_8536_SDA")
			(options
				(clearance outline)
				(anchor circle)
			)
			(primitives
				(gr_poly
					(pts
						(arc
							(start -0.1778 -0.2794)
							(mid -0.249642 -0.249642)
							(end -0.2794 -0.1778)
						)
						(arc
							(start -0.2794 0.1778)
							(mid -0.249642 0.249642)
							(end -0.1778 0.2794)
						)
						(arc
							(start 0.1778 0.2794)
							(mid 0.249642 0.249642)
							(end 0.2794 0.1778)
						)
						(arc
							(start 0.2794 -0.1778)
							(mid 0.249642 -0.249642)
							(end 0.1778 -0.2794)
						)
					)
					(width 0)
					(fill yes)
				)
			)
		)
	)
	(footprint ""
		(layer "F.Cu")
		(at 185.008266 -212.420454 180)
		(property "Reference" "C126"
			(at 0 0 180)
			(layer "F.SilkS")
			(hide yes)
			(effects
				(font
					(size 1.27 1.27)
				)
			)
		)
		(property "Value" "SCD22U10V2KX-1GP"
			(at 1.1811 -2.7051 180)
			(unlocked yes)
			(layer "F.Fab")
			(hide yes)
			(effects
				(font
					(size 1.016 1.016)
					(thickness 0.1524)
				)
			)
		)
		(property "Device Type" "C402H22"
			(at 1.1811 -4.2291 180)
			(unlocked yes)
			(layer "F.Fab")
			(hide yes)
			(effects
				(font
					(size 1.016 1.016)
					(thickness 0.1524)
				)
			)
		)
		(duplicate_pad_numbers_are_jumpers no)
		(fp_rect
			(start -0.4318 0.9525)
			(end 0.4318 -0.9525)
			(stroke
				(width 0)
				(type default)
			)
			(fill no)
			(layer "F.CrtYd")
		)
		(fp_rect
			(start -0.4318 0.9525)
			(end 0.4318 -0.9525)
			(stroke
				(width 0)
				(type default)
			)
			(fill no)
			(layer "F.Fab")
		)
		(pad "1" smd custom
			(at 0 -0.4445 180)
			(size 0.1524 0.1524)
			(layers "F.Cu" "F.Mask" "F.Paste")
			(net "PCIE_TX_CAP_N47")
			(options
				(clearance outline)
				(anchor circle)
			)
			(primitives
				(gr_poly
					(pts
						(arc
							(start 0.3048 -0.2032)
							(mid 0.275042 -0.275042)
							(end 0.2032 -0.3048)
						)
						(arc
							(start -0.2032 -0.3048)
							(mid -0.275042 -0.275042)
							(end -0.3048 -0.2032)
						)
						(arc
							(start -0.3048 0.2032)
							(mid -0.275042 0.275042)
							(end -0.2032 0.3048)
						)
						(arc
							(start 0.2032 0.3048)
							(mid 0.275042 0.275042)
							(end 0.3048 0.2032)
						)
					)
					(width 0)
					(fill yes)
				)
			)
		)
		(pad "2" smd custom
			(at 0 0.4445 180)
			(size 0.1524 0.1524)
			(layers "F.Cu" "F.Mask" "F.Paste")
			(net "PCIE_TX_N47")
			(options
				(clearance outline)
				(anchor circle)
			)
			(primitives
				(gr_poly
					(pts
						(arc
							(start 0.3048 -0.2032)
							(mid 0.275042 -0.275042)
							(end 0.2032 -0.3048)
						)
						(arc
							(start -0.2032 -0.3048)
							(mid -0.275042 -0.275042)
							(end -0.3048 -0.2032)
						)
						(arc
							(start -0.3048 0.2032)
							(mid -0.275042 0.275042)
							(end -0.2032 0.3048)
						)
						(arc
							(start 0.2032 0.3048)
							(mid 0.275042 0.275042)
							(end 0.3048 0.2032)
						)
					)
					(width 0)
					(fill yes)
				)
			)
		)
	)
	(footprint ""
		(layer "F.Cu")
		(at 34.3535 -112.26546 180)
		(property "Reference" "R507"
			(at 0 0 180)
			(layer "F.SilkS")
			(hide yes)
			(effects
				(font
					(size 1.27 1.27)
				)
			)
		)
		(property "Value" "0R2J-2-GP"
			(at 0.064008 -3.993896 180)
			(unlocked yes)
			(layer "F.Fab")
			(hide yes)
			(effects
				(font
					(size 1.016 1.016)
					(thickness 0.1524)
				)
			)
		)
		(property "Device Type" "R402H16"
			(at 0.064008 -5.517896 180)
			(unlocked yes)
			(layer "F.Fab")
			(hide yes)
			(effects
				(font
					(size 1.016 1.016)
					(thickness 0.1524)
				)
			)
		)
		(duplicate_pad_numbers_are_jumpers no)
		(fp_line
			(start 0.508 -0.9398)
			(end -0.508 -0.9398)
			(stroke
				(width 0.1524)
				(type default)
			)
			(layer "F.SilkS")
		)
		(fp_line
			(start -0.508 -0.9398)
			(end -0.508 0.9398)
			(stroke
				(width 0.1524)
				(type default)
			)
			(layer "F.SilkS")
		)
		(fp_rect
			(start -0.508 0.9398)
			(end 0.508 -0.9398)
			(stroke
				(width 0)
				(type default)
			)
			(fill no)
			(layer "F.CrtYd")
		)
		(fp_rect
			(start -0.508 0.9398)
			(end 0.508 -0.9398)
			(stroke
				(width 0)
				(type default)
			)
			(fill no)
			(layer "F.Fab")
		)
		(pad "1" smd custom
			(at 0 -0.4445 180)
			(size 0.1397 0.1397)
			(layers "F.Cu" "F.Mask" "F.Paste")
			(net "BMC_ADD1")
			(options
				(clearance outline)
				(anchor circle)
			)
			(primitives
				(gr_poly
					(pts
						(arc
							(start -0.1778 -0.2794)
							(mid -0.249642 -0.249642)
							(end -0.2794 -0.1778)
						)
						(arc
							(start -0.2794 0.1778)
							(mid -0.249642 0.249642)
							(end -0.1778 0.2794)
						)
						(arc
							(start 0.1778 0.2794)
							(mid 0.249642 0.249642)
							(end 0.2794 0.1778)
						)
						(arc
							(start 0.2794 -0.1778)
							(mid 0.249642 -0.249642)
							(end 0.1778 -0.2794)
						)
					)
					(width 0)
					(fill yes)
				)
			)
		)
		(pad "2" smd custom
			(at 0 0.4445 180)
			(size 0.1397 0.1397)
			(layers "F.Cu" "F.Mask" "F.Paste")
			(net "BMC_ADD1_R")
			(options
				(clearance outline)
				(anchor circle)
			)
			(primitives
				(gr_poly
					(pts
						(arc
							(start -0.1778 -0.2794)
							(mid -0.249642 -0.249642)
							(end -0.2794 -0.1778)
						)
						(arc
							(start -0.2794 0.1778)
							(mid -0.249642 0.249642)
							(end -0.1778 0.2794)
						)
						(arc
							(start 0.1778 0.2794)
							(mid 0.249642 0.249642)
							(end 0.2794 0.1778)
						)
						(arc
							(start 0.2794 -0.1778)
							(mid 0.249642 -0.249642)
							(end 0.1778 -0.2794)
						)
					)
					(width 0)
					(fill yes)
				)
			)
		)
	)
	(footprint ""
		(layer "F.Cu")
		(at 139.115546 -73.931526 90)
		(property "Reference" "R959"
			(at 0 0 90)
			(layer "F.SilkS")
			(hide yes)
			(effects
				(font
					(size 1.27 1.27)
				)
			)
		)
		(property "Value" "33R2J-2-GP"
			(at 0.064008 -3.993896 90)
			(unlocked yes)
			(layer "F.Fab")
			(hide yes)
			(effects
				(font
					(size 1.016 1.016)
					(thickness 0.1524)
				)
			)
		)
		(property "Device Type" "R402H16"
			(at 0.064008 -5.517896 90)
			(unlocked yes)
			(layer "F.Fab")
			(hide yes)
			(effects
				(font
					(size 1.016 1.016)
					(thickness 0.1524)
				)
			)
		)
		(duplicate_pad_numbers_are_jumpers no)
		(fp_line
			(start 0.508 -0.9398)
			(end -0.508 -0.9398)
			(stroke
				(width 0.1524)
				(type default)
			)
			(layer "F.SilkS")
		)
		(fp_line
			(start -0.508 -0.9398)
			(end -0.508 0.9398)
			(stroke
				(width 0.1524)
				(type default)
			)
			(layer "F.SilkS")
		)
		(fp_rect
			(start -0.508 0.9398)
			(end 0.508 -0.9398)
			(stroke
				(width 0)
				(type default)
			)
			(fill no)
			(layer "F.CrtYd")
		)
		(fp_rect
			(start -0.508 0.9398)
			(end 0.508 -0.9398)
			(stroke
				(width 0)
				(type default)
			)
			(fill no)
			(layer "F.Fab")
		)
		(pad "1" smd custom
			(at 0 -0.4445 90)
			(size 0.1397 0.1397)
			(layers "F.Cu" "F.Mask" "F.Paste")
			(net "SPI_DATA0_0_R")
			(options
				(clearance outline)
				(anchor circle)
			)
			(primitives
				(gr_poly
					(pts
						(arc
							(start -0.1778 -0.2794)
							(mid -0.249642 -0.249642)
							(end -0.2794 -0.1778)
						)
						(arc
							(start -0.2794 0.1778)
							(mid -0.249642 0.249642)
							(end -0.1778 0.2794)
						)
						(arc
							(start 0.1778 0.2794)
							(mid 0.249642 0.249642)
							(end 0.2794 0.1778)
						)
						(arc
							(start 0.2794 -0.1778)
							(mid 0.249642 -0.249642)
							(end 0.1778 -0.2794)
						)
					)
					(width 0)
					(fill yes)
				)
			)
		)
		(pad "2" smd custom
			(at 0 0.4445 90)
			(size 0.1397 0.1397)
			(layers "F.Cu" "F.Mask" "F.Paste")
			(net "SPI_DATA0_0")
			(options
				(clearance outline)
				(anchor circle)
			)
			(primitives
				(gr_poly
					(pts
						(arc
							(start -0.1778 -0.2794)
							(mid -0.249642 -0.249642)
							(end -0.2794 -0.1778)
						)
						(arc
							(start -0.2794 0.1778)
							(mid -0.249642 0.249642)
							(end -0.1778 0.2794)
						)
						(arc
							(start 0.1778 0.2794)
							(mid 0.249642 0.249642)
							(end 0.2794 0.1778)
						)
						(arc
							(start 0.2794 -0.1778)
							(mid 0.249642 -0.249642)
							(end 0.1778 -0.2794)
						)
					)
					(width 0)
					(fill yes)
				)
			)
		)
	)
)
